(kicad_pcb
	(version 20260206)
	(generator "pcbnew")
	(generator_version "10.0")
	(general
		(thickness 1.6)
		(legacy_teardrops no)
	)
	(paper "A4")
	(title_block
		(title "01162023_DA0F0TEBIF0_F0T_Expander_BD_F_brd_V02_OCP.brd")
		(comment 1 "Grand Teton / footprints 6633-6638 of 9728")
	)
	(layers
		(0 "F.Cu" signal "TOP")
		(4 "In1.Cu" signal "GND")
		(6 "In2.Cu" signal "VCC")
		(8 "In3.Cu" signal "VCC1")
		(10 "In4.Cu" signal "GND1")
		(12 "In5.Cu" signal "IN1")
		(14 "In6.Cu" signal "GND2")
		(16 "In7.Cu" signal "IN2")
		(18 "In8.Cu" signal "GND3")
		(20 "In9.Cu" signal "IN3")
		(22 "In10.Cu" signal "GND4")
		(24 "In11.Cu" signal "IN4")
		(26 "In12.Cu" signal "GND5")
		(28 "In13.Cu" signal "IN5")
		(30 "In14.Cu" signal "GND6")
		(32 "In15.Cu" signal "IN6")
		(34 "In16.Cu" signal "GND7")
		(2 "B.Cu" signal "BOTTOM")
		(9 "F.Adhes" user "F.Adhesive")
		(11 "B.Adhes" user "B.Adhesive")
		(13 "F.Paste" user "Package Geometry/Pastemask Top")
		(15 "B.Paste" user "Package Geometry/Pastemask Bottom")
		(5 "F.SilkS" user "Ref Des/Silkscreen Top")
		(7 "B.SilkS" user "Ref Des/Silkscreen Bottom")
		(1 "F.Mask" user "Board Geometry/Soldermask Top")
		(3 "B.Mask" user "Board Geometry/Soldermask Bottom")
		(17 "Dwgs.User" user "User.Drawings")
		(19 "Cmts.User" user "User.Comments")
		(21 "Eco1.User" user "User.Eco1")
		(23 "Eco2.User" user "User.Eco2")
		(25 "Edge.Cuts" user "Board Geometry/Outline")
		(27 "Margin" user)
		(31 "F.CrtYd" user "Package Geometry/Place Bound Top")
		(29 "B.CrtYd" user "Package Geometry/Place Bound Bottom")
		(35 "F.Fab" user "Ref Des/Assembly Top")
		(33 "B.Fab" user "Ref Des/Assembly Bottom")
	)
	(footprint ""
		(layer "F.Cu")
		(at 78.243684 -42.84091)
		(property "Reference" "R528"
			(at 0 0 0)
			(layer "F.SilkS")
			(hide yes)
			(effects
				(font
					(size 1.27 1.27)
				)
			)
		)
		(property "Value" ""
			(at 0 0 0)
			(layer "F.Fab")
			(effects
				(font
					(size 1.27 1.27)
				)
			)
		)
		(duplicate_pad_numbers_are_jumpers no)
		(fp_line
			(start -0.7874 -0.4064)
			(end 0.7874 -0.4064)
			(stroke
				(width 0.1524)
				(type default)
			)
			(layer "F.SilkS")
		)
		(fp_line
			(start -0.7874 0.4064)
			(end -0.7874 -0.4064)
			(stroke
				(width 0.1524)
				(type default)
			)
			(layer "F.SilkS")
		)
		(fp_line
			(start 0.7874 -0.4064)
			(end 0.7874 0.4064)
			(stroke
				(width 0.1524)
				(type default)
			)
			(layer "F.SilkS")
		)
		(fp_line
			(start 0.7874 0.4064)
			(end -0.7874 0.4064)
			(stroke
				(width 0.1524)
				(type default)
			)
			(layer "F.SilkS")
		)
		(fp_line
			(start -0.67945 -0.305054)
			(end -0.12065 -0.305054)
			(stroke
				(width 0.1)
				(type default)
			)
			(layer "F.Fab")
		)
		(fp_line
			(start -0.67945 0.3048)
			(end -0.67945 -0.305054)
			(stroke
				(width 0.1)
				(type default)
			)
			(layer "F.Fab")
		)
		(fp_line
			(start -0.12065 -0.305054)
			(end -0.12065 -0.2794)
			(stroke
				(width 0.1)
				(type default)
			)
			(layer "F.Fab")
		)
		(fp_line
			(start -0.12065 -0.2794)
			(end 0.12065 -0.2794)
			(stroke
				(width 0.1)
				(type default)
			)
			(layer "F.Fab")
		)
		(fp_line
			(start -0.12065 0.2794)
			(end -0.12065 0.3048)
			(stroke
				(width 0.1)
				(type default)
			)
			(layer "F.Fab")
		)
		(fp_line
			(start -0.12065 0.3048)
			(end -0.67945 0.3048)
			(stroke
				(width 0.1)
				(type default)
			)
			(layer "F.Fab")
		)
		(fp_line
			(start 0.120396 0.2794)
			(end -0.12065 0.2794)
			(stroke
				(width 0.1)
				(type default)
			)
			(layer "F.Fab")
		)
		(fp_line
			(start 0.120396 0.3048)
			(end 0.120396 0.2794)
			(stroke
				(width 0.1)
				(type default)
			)
			(layer "F.Fab")
		)
		(fp_line
			(start 0.12065 -0.3048)
			(end 0.67945 -0.3048)
			(stroke
				(width 0.1)
				(type default)
			)
			(layer "F.Fab")
		)
		(fp_line
			(start 0.12065 -0.2794)
			(end 0.12065 -0.3048)
			(stroke
				(width 0.1)
				(type default)
			)
			(layer "F.Fab")
		)
		(fp_line
			(start 0.67945 -0.3048)
			(end 0.67945 0.3048)
			(stroke
				(width 0.1)
				(type default)
			)
			(layer "F.Fab")
		)
		(fp_line
			(start 0.67945 0.3048)
			(end 0.120396 0.3048)
			(stroke
				(width 0.1)
				(type default)
			)
			(layer "F.Fab")
		)
		(pad "1" smd circle
			(at -0.40005 0)
			(size 0 0)
			(layers "F.Cu" "F.Mask" "F.Paste")
			(net "SSD2_ADC_A1")
		)
		(pad "2" smd circle
			(at 0.40005 0)
			(size 0 0)
			(layers "F.Cu" "F.Mask" "F.Paste")
			(net "P3V3_AUX")
		)
	)
	(footprint ""
		(layer "F.Cu")
		(at 190.78956 -402.66874 90)
		(property "Reference" "R4418"
			(at 0 0 90)
			(layer "F.SilkS")
			(hide yes)
			(effects
				(font
					(size 1.27 1.27)
				)
			)
		)
		(property "Value" ""
			(at 0 0 90)
			(layer "F.Fab")
			(effects
				(font
					(size 1.27 1.27)
				)
			)
		)
		(duplicate_pad_numbers_are_jumpers no)
		(fp_line
			(start 0.7874 -0.4064)
			(end 0.7874 0.4064)
			(stroke
				(width 0.1524)
				(type default)
			)
			(layer "F.SilkS")
		)
		(fp_line
			(start -0.7874 -0.4064)
			(end 0.7874 -0.4064)
			(stroke
				(width 0.1524)
				(type default)
			)
			(layer "F.SilkS")
		)
		(fp_line
			(start 0.7874 0.4064)
			(end -0.7874 0.4064)
			(stroke
				(width 0.1524)
				(type default)
			)
			(layer "F.SilkS")
		)
		(fp_line
			(start -0.7874 0.4064)
			(end -0.7874 -0.4064)
			(stroke
				(width 0.1524)
				(type default)
			)
			(layer "F.SilkS")
		)
		(fp_line
			(start -0.12065 -0.305054)
			(end -0.12065 -0.2794)
			(stroke
				(width 0.1)
				(type default)
			)
			(layer "F.Fab")
		)
		(fp_line
			(start -0.67945 -0.305054)
			(end -0.12065 -0.305054)
			(stroke
				(width 0.1)
				(type default)
			)
			(layer "F.Fab")
		)
		(fp_line
			(start 0.67945 -0.3048)
			(end 0.67945 0.3048)
			(stroke
				(width 0.1)
				(type default)
			)
			(layer "F.Fab")
		)
		(fp_line
			(start 0.12065 -0.3048)
			(end 0.67945 -0.3048)
			(stroke
				(width 0.1)
				(type default)
			)
			(layer "F.Fab")
		)
		(fp_line
			(start 0.12065 -0.2794)
			(end 0.12065 -0.3048)
			(stroke
				(width 0.1)
				(type default)
			)
			(layer "F.Fab")
		)
		(fp_line
			(start -0.12065 -0.2794)
			(end 0.12065 -0.2794)
			(stroke
				(width 0.1)
				(type default)
			)
			(layer "F.Fab")
		)
		(fp_line
			(start 0.120396 0.2794)
			(end -0.12065 0.2794)
			(stroke
				(width 0.1)
				(type default)
			)
			(layer "F.Fab")
		)
		(fp_line
			(start -0.12065 0.2794)
			(end -0.12065 0.3048)
			(stroke
				(width 0.1)
				(type default)
			)
			(layer "F.Fab")
		)
		(fp_line
			(start 0.67945 0.3048)
			(end 0.120396 0.3048)
			(stroke
				(width 0.1)
				(type default)
			)
			(layer "F.Fab")
		)
		(fp_line
			(start 0.120396 0.3048)
			(end 0.120396 0.2794)
			(stroke
				(width 0.1)
				(type default)
			)
			(layer "F.Fab")
		)
		(fp_line
			(start -0.12065 0.3048)
			(end -0.67945 0.3048)
			(stroke
				(width 0.1)
				(type default)
			)
			(layer "F.Fab")
		)
		(fp_line
			(start -0.67945 0.3048)
			(end -0.67945 -0.305054)
			(stroke
				(width 0.1)
				(type default)
			)
			(layer "F.Fab")
		)
		(pad "1" smd circle
			(at -0.40005 0 90)
			(size 0 0)
			(layers "F.Cu" "F.Mask" "F.Paste")
			(net "GND")
		)
		(pad "2" smd circle
			(at 0.40005 0 90)
			(size 0 0)
			(layers "F.Cu" "F.Mask" "F.Paste")
			(net "A_P12V_AUX_ADR_TRIGGER")
		)
	)
	(footprint ""
		(layer "F.Cu")
		(at 27.126184 -39.73576 -90)
		(property "Reference" "R5542"
			(at 0 0 270)
			(layer "F.SilkS")
			(hide yes)
			(effects
				(font
					(size 1.27 1.27)
				)
			)
		)
		(property "Value" ""
			(at 0 0 270)
			(layer "F.Fab")
			(effects
				(font
					(size 1.27 1.27)
				)
			)
		)
		(duplicate_pad_numbers_are_jumpers no)
		(fp_line
			(start -0.7874 0.4064)
			(end -0.7874 -0.4064)
			(stroke
				(width 0.1524)
				(type default)
			)
			(layer "F.SilkS")
		)
		(fp_line
			(start 0.7874 0.4064)
			(end -0.7874 0.4064)
			(stroke
				(width 0.1524)
				(type default)
			)
			(layer "F.SilkS")
		)
		(fp_line
			(start -0.7874 -0.4064)
			(end 0.7874 -0.4064)
			(stroke
				(width 0.1524)
				(type default)
			)
			(layer "F.SilkS")
		)
		(fp_line
			(start 0.7874 -0.4064)
			(end 0.7874 0.4064)
			(stroke
				(width 0.1524)
				(type default)
			)
			(layer "F.SilkS")
		)
		(fp_line
			(start -0.67945 0.3048)
			(end -0.67945 -0.305054)
			(stroke
				(width 0.1)
				(type default)
			)
			(layer "F.Fab")
		)
		(fp_line
			(start -0.12065 0.3048)
			(end -0.67945 0.3048)
			(stroke
				(width 0.1)
				(type default)
			)
			(layer "F.Fab")
		)
		(fp_line
			(start 0.120396 0.3048)
			(end 0.120396 0.2794)
			(stroke
				(width 0.1)
				(type default)
			)
			(layer "F.Fab")
		)
		(fp_line
			(start 0.67945 0.3048)
			(end 0.120396 0.3048)
			(stroke
				(width 0.1)
				(type default)
			)
			(layer "F.Fab")
		)
		(fp_line
			(start -0.12065 0.2794)
			(end -0.12065 0.3048)
			(stroke
				(width 0.1)
				(type default)
			)
			(layer "F.Fab")
		)
		(fp_line
			(start 0.120396 0.2794)
			(end -0.12065 0.2794)
			(stroke
				(width 0.1)
				(type default)
			)
			(layer "F.Fab")
		)
		(fp_line
			(start -0.12065 -0.2794)
			(end 0.12065 -0.2794)
			(stroke
				(width 0.1)
				(type default)
			)
			(layer "F.Fab")
		)
		(fp_line
			(start 0.12065 -0.2794)
			(end 0.12065 -0.3048)
			(stroke
				(width 0.1)
				(type default)
			)
			(layer "F.Fab")
		)
		(fp_line
			(start 0.12065 -0.3048)
			(end 0.67945 -0.3048)
			(stroke
				(width 0.1)
				(type default)
			)
			(layer "F.Fab")
		)
		(fp_line
			(start 0.67945 -0.3048)
			(end 0.67945 0.3048)
			(stroke
				(width 0.1)
				(type default)
			)
			(layer "F.Fab")
		)
		(fp_line
			(start -0.67945 -0.305054)
			(end -0.12065 -0.305054)
			(stroke
				(width 0.1)
				(type default)
			)
			(layer "F.Fab")
		)
		(fp_line
			(start -0.12065 -0.305054)
			(end -0.12065 -0.2794)
			(stroke
				(width 0.1)
				(type default)
			)
			(layer "F.Fab")
		)
		(pad "1" smd circle
			(at -0.40005 0 270)
			(size 0 0)
			(layers "F.Cu" "F.Mask" "F.Paste")
			(net "P3V3_AUX")
		)
		(pad "2" smd circle
			(at 0.40005 0 270)
			(size 0 0)
			(layers "F.Cu" "F.Mask" "F.Paste")
			(net "SSD1_AUX_P3V3_EN")
		)
	)
	(footprint ""
		(layer "F.Cu")
		(at 333.965042 -308.617112 -90)
		(property "Reference" "C4303"
			(at 0 0 270)
			(layer "F.SilkS")
			(hide yes)
			(effects
				(font
					(size 1.27 1.27)
				)
			)
		)
		(property "Value" ""
			(at 0 0 270)
			(layer "F.Fab")
			(effects
				(font
					(size 1.27 1.27)
				)
			)
		)
		(duplicate_pad_numbers_are_jumpers no)
		(fp_line
			(start -1.2954 0.5842)
			(end -1.2954 -0.5842)
			(stroke
				(width 0.1524)
				(type default)
			)
			(layer "F.SilkS")
		)
		(fp_line
			(start 1.2954 0.5842)
			(end -1.2954 0.5842)
			(stroke
				(width 0.1524)
				(type default)
			)
			(layer "F.SilkS")
		)
		(fp_line
			(start -1.2954 -0.5842)
			(end 1.2954 -0.5842)
			(stroke
				(width 0.1524)
				(type default)
			)
			(layer "F.SilkS")
		)
		(fp_line
			(start 1.2954 -0.5842)
			(end 1.2954 0.5842)
			(stroke
				(width 0.1524)
				(type default)
			)
			(layer "F.SilkS")
		)
		(fp_line
			(start -0.8636 0.4572)
			(end -0.8636 0.4064)
			(stroke
				(width 0.1)
				(type default)
			)
			(layer "F.Fab")
		)
		(fp_line
			(start 0.8636 0.4572)
			(end -0.8636 0.4572)
			(stroke
				(width 0.1)
				(type default)
			)
			(layer "F.Fab")
		)
		(fp_line
			(start -1.1938 0.4064)
			(end -1.1938 -0.4064)
			(stroke
				(width 0.1)
				(type default)
			)
			(layer "F.Fab")
		)
		(fp_line
			(start -0.8636 0.4064)
			(end -1.1938 0.4064)
			(stroke
				(width 0.1)
				(type default)
			)
			(layer "F.Fab")
		)
		(fp_line
			(start 0.8636 0.4064)
			(end 0.8636 0.4572)
			(stroke
				(width 0.1)
				(type default)
			)
			(layer "F.Fab")
		)
		(fp_line
			(start 1.1938 0.4064)
			(end 0.8636 0.4064)
			(stroke
				(width 0.1)
				(type default)
			)
			(layer "F.Fab")
		)
		(fp_line
			(start -1.1938 -0.4064)
			(end -0.8636 -0.4064)
			(stroke
				(width 0.1)
				(type default)
			)
			(layer "F.Fab")
		)
		(fp_line
			(start -0.8636 -0.4064)
			(end -0.8636 -0.4572)
			(stroke
				(width 0.1)
				(type default)
			)
			(layer "F.Fab")
		)
		(fp_line
			(start 0.8636 -0.4064)
			(end 1.1938 -0.4064)
			(stroke
				(width 0.1)
				(type default)
			)
			(layer "F.Fab")
		)
		(fp_line
			(start 1.1938 -0.4064)
			(end 1.1938 0.4064)
			(stroke
				(width 0.1)
				(type default)
			)
			(layer "F.Fab")
		)
		(fp_line
			(start -0.8636 -0.4572)
			(end 0.8636 -0.4572)
			(stroke
				(width 0.1)
				(type default)
			)
			(layer "F.Fab")
		)
		(fp_line
			(start 0.8636 -0.4572)
			(end 0.8636 -0.4064)
			(stroke
				(width 0.1)
				(type default)
			)
			(layer "F.Fab")
		)
		(pad "1" smd rect
			(at -0.7366 0 180)
			(size 0.7112 0.8128)
			(layers "F.Cu" "F.Mask" "F.Paste")
			(net "P0V8_PEX2")
		)
		(pad "2" smd rect
			(at 0.7366 0 180)
			(size 0.7112 0.8128)
			(layers "F.Cu" "F.Mask" "F.Paste")
			(net "GND")
		)
	)
	(footprint ""
		(layer "F.Cu")
		(at 251.671836 -369.875562 90)
		(property "Reference" "PQ6603"
			(at -8.232394 -2.673604 0)
			(unlocked yes)
			(layer "F.SilkS")
			(effects
				(font
					(size 0.7874 0.5842)
					(thickness 0.1524)
				)
				(justify left)
			)
		)
		(property "Value" ""
			(at 0 0 90)
			(layer "F.Fab")
			(effects
				(font
					(size 1.27 1.27)
				)
			)
		)
		(duplicate_pad_numbers_are_jumpers no)
		(fp_line
			(start 2.350008 -2.649982)
			(end 2.350008 -2.4892)
			(stroke
				(width 0.1524)
				(type default)
			)
			(layer "F.SilkS")
		)
		(fp_line
			(start -2.350008 -2.649982)
			(end 2.350008 -2.649982)
			(stroke
				(width 0.1524)
				(type default)
			)
			(layer "F.SilkS")
		)
		(fp_line
			(start -2.350008 -2.4384)
			(end -2.350008 -2.649982)
			(stroke
				(width 0.1524)
				(type default)
			)
			(layer "F.SilkS")
		)
		(fp_line
			(start 2.350008 2.4892)
			(end 2.350008 2.649982)
			(stroke
				(width 0.1524)
				(type default)
			)
			(layer "F.SilkS")
		)
		(fp_line
			(start 2.350008 2.649982)
			(end -2.350008 2.649982)
			(stroke
				(width 0.1524)
				(type default)
			)
			(layer "F.SilkS")
		)
		(fp_line
			(start -2.350008 2.649982)
			(end -2.350008 2.413)
			(stroke
				(width 0.1524)
				(type default)
			)
			(layer "F.SilkS")
		)
		(fp_poly
			(pts
				(xy -4.77393 -1.889252) (xy -5.81533 -2.308352) (xy -5.81533 -1.508252)
			)
			(stroke
				(width 0)
				(type default)
			)
			(fill yes)
			(layer "F.SilkS")
		)
		(fp_line
			(start 2.350008 -2.649982)
			(end 2.350008 2.649982)
			(stroke
				(width 0.1)
				(type default)
			)
			(layer "F.Fab")
		)
		(fp_line
			(start -2.350008 -2.649982)
			(end 2.350008 -2.649982)
			(stroke
				(width 0.1)
				(type default)
			)
			(layer "F.Fab")
		)
		(fp_line
			(start 2.350008 2.649982)
			(end -2.350008 2.649982)
			(stroke
				(width 0.1)
				(type default)
			)
			(layer "F.Fab")
		)
		(fp_line
			(start -2.350008 2.649982)
			(end -2.350008 -2.649982)
			(stroke
				(width 0.1)
				(type default)
			)
			(layer "F.Fab")
		)
		(fp_poly
			(pts
				(xy -3.717544 -1.905) (xy -4.758944 -2.3241) (xy -4.758944 -1.524)
			)
			(stroke
				(width 0)
				(type default)
			)
			(fill yes)
			(layer "F.Fab")
		)
		(pad "1" smd rect
			(at -2.999994 -1.905)
			(size 0.7112 1.1684)
			(layers "F.Cu" "F.Mask" "F.Paste")
			(net "P12V_AUX")
		)
		(pad "2" smd rect
			(at -2.999994 -0.635)
			(size 0.7112 1.1684)
			(layers "F.Cu" "F.Mask" "F.Paste")
			(net "P12V_AUX")
		)
		(pad "3" smd rect
			(at -2.999994 0.635)
			(size 0.7112 1.1684)
			(layers "F.Cu" "F.Mask" "F.Paste")
			(net "P12V_AUX")
		)
		(pad "4" smd rect
			(at -2.999994 1.905)
			(size 0.7112 1.1684)
			(layers "F.Cu" "F.Mask" "F.Paste")
			(net "HS_GATE2_R_2")
		)
		(pad "5" smd circle
			(at 0.925068 0)
			(size 0 0)
			(layers "F.Cu" "F.Mask" "F.Paste")
			(net "P12V_STBY_R2")
		)
		(zone
			(layer "F.Cu")
			(hatch none 0.5)
			(connect_pads
				(clearance 0)
			)
			(min_thickness 0.25)
			(keepout
				(tracks not_allowed)
				(vias allowed)
				(pads allowed)
				(copperpour not_allowed)
				(footprints allowed)
			)
			(placement
				(enabled no)
				(sheetname "")
			)
			(fill
				(thermal_gap 0.5)
				(thermal_bridge_width 0.5)
				(island_removal_mode 0)
			)
			(polygon
				(pts
					(xy 249.512836 -368.427762) (xy 253.830836 -368.427762) (xy 254.313436 -368.427762) (xy 254.313436 -367.526062)
					(xy 249.030236 -367.526062) (xy 249.030236 -368.427762)
				)
			)
		)
	)
	(footprint ""
		(layer "F.Cu")
		(at 256.681986 -37.025072)
		(property "Reference" "R5681"
			(at 0 0 0)
			(layer "F.SilkS")
			(hide yes)
			(effects
				(font
					(size 1.27 1.27)
				)
			)
		)
		(property "Value" ""
			(at 0 0 0)
			(layer "F.Fab")
			(effects
				(font
					(size 1.27 1.27)
				)
			)
		)
		(duplicate_pad_numbers_are_jumpers no)
		(fp_line
			(start -0.7874 -0.4064)
			(end 0.7874 -0.4064)
			(stroke
				(width 0.1524)
				(type default)
			)
			(layer "F.SilkS")
		)
		(fp_line
			(start -0.7874 0.4064)
			(end -0.7874 -0.4064)
			(stroke
				(width 0.1524)
				(type default)
			)
			(layer "F.SilkS")
		)
		(fp_line
			(start 0.7874 -0.4064)
			(end 0.7874 0.4064)
			(stroke
				(width 0.1524)
				(type default)
			)
			(layer "F.SilkS")
		)
		(fp_line
			(start 0.7874 0.4064)
			(end -0.7874 0.4064)
			(stroke
				(width 0.1524)
				(type default)
			)
			(layer "F.SilkS")
		)
		(fp_line
			(start -0.67945 -0.305054)
			(end -0.12065 -0.305054)
			(stroke
				(width 0.1)
				(type default)
			)
			(layer "F.Fab")
		)
		(fp_line
			(start -0.67945 0.3048)
			(end -0.67945 -0.305054)
			(stroke
				(width 0.1)
				(type default)
			)
			(layer "F.Fab")
		)
		(fp_line
			(start -0.12065 -0.305054)
			(end -0.12065 -0.2794)
			(stroke
				(width 0.1)
				(type default)
			)
			(layer "F.Fab")
		)
		(fp_line
			(start -0.12065 -0.2794)
			(end 0.12065 -0.2794)
			(stroke
				(width 0.1)
				(type default)
			)
			(layer "F.Fab")
		)
		(fp_line
			(start -0.12065 0.2794)
			(end -0.12065 0.3048)
			(stroke
				(width 0.1)
				(type default)
			)
			(layer "F.Fab")
		)
		(fp_line
			(start -0.12065 0.3048)
			(end -0.67945 0.3048)
			(stroke
				(width 0.1)
				(type default)
			)
			(layer "F.Fab")
		)
		(fp_line
			(start 0.120396 0.2794)
			(end -0.12065 0.2794)
			(stroke
				(width 0.1)
				(type default)
			)
			(layer "F.Fab")
		)
		(fp_line
			(start 0.120396 0.3048)
			(end 0.120396 0.2794)
			(stroke
				(width 0.1)
				(type default)
			)
			(layer "F.Fab")
		)
		(fp_line
			(start 0.12065 -0.3048)
			(end 0.67945 -0.3048)
			(stroke
				(width 0.1)
				(type default)
			)
			(layer "F.Fab")
		)
		(fp_line
			(start 0.12065 -0.2794)
			(end 0.12065 -0.3048)
			(stroke
				(width 0.1)
				(type default)
			)
			(layer "F.Fab")
		)
		(fp_line
			(start 0.67945 -0.3048)
			(end 0.67945 0.3048)
			(stroke
				(width 0.1)
				(type default)
			)
			(layer "F.Fab")
		)
		(fp_line
			(start 0.67945 0.3048)
			(end 0.120396 0.3048)
			(stroke
				(width 0.1)
				(type default)
			)
			(layer "F.Fab")
		)
		(pad "1" smd circle
			(at -0.40005 0)
			(size 0 0)
			(layers "F.Cu" "F.Mask" "F.Paste")
			(net "RST_SMB_SSD_R_N")
		)
		(pad "2" smd circle
			(at 0.40005 0)
			(size 0 0)
			(layers "F.Cu" "F.Mask" "F.Paste")
			(net "RST_SMB_SSD9_N")
		)
	)
)
